# S9S_MB_2U (Grand Teton) — schematic netlist excerpt (pin names and nets, part order shuffled) for the footprints in the layout excerpt that follows; sources: Cadence DE-HDL packaged netlist, KiCad conversion of 03242023_DA0F0TMBIJ0_F0T_Motherboard_J_brd_V01_OCP.brd

R341  Q_RES  0 5% CHIP  pkg 0402LF  page 225 : A = H_CPU1_ERR1_LVC1_R_N ; B = H_CPU_ERR1_LVC1_R_N
R4707  Q_RES  560 1% CHIP  pkg 0402LF  page 255 : A = LED_P12V_PSU_R3 ; B = P12V_PSU
PC1237  Q_CAP  22UF 4V 20% X6S  pkg C0805  page 263 : A = P1V8_PCH_AUX ; B = GND

(kicad_pcb
	(version 20260206)
	(generator "pcbnew")
	(generator_version "10.0")
	(general
		(thickness 1.6)
		(legacy_teardrops no)
	)
	(paper "A4")
	(title_block
		(title "03242023_DA0F0TMBIJ0_F0T_Motherboard_J_brd_V01_OCP.brd")
		(comment 1 "Grand Teton / footprints 4427-4429 of 6105")
	)
	(layers
		(0 "F.Cu" signal "TOP")
		(4 "In1.Cu" signal "GND")
		(6 "In2.Cu" signal "IN1")
		(8 "In3.Cu" signal "GND1")
		(10 "In4.Cu" signal "IN2")
		(12 "In5.Cu" signal "GND2")
		(14 "In6.Cu" signal "IN3")
		(16 "In7.Cu" signal "GND3")
		(18 "In8.Cu" signal "VCC")
		(20 "In9.Cu" signal "VCC1")
		(22 "In10.Cu" signal "GND4")
		(24 "In11.Cu" signal "IN4")
		(26 "In12.Cu" signal "GND5")
		(28 "In13.Cu" signal "IN5")
		(30 "In14.Cu" signal "GND6")
		(32 "In15.Cu" signal "IN6")
		(34 "In16.Cu" signal "GND7")
		(2 "B.Cu" signal "BOTTOM")
		(9 "F.Adhes" user "F.Adhesive")
		(11 "B.Adhes" user "B.Adhesive")
		(13 "F.Paste" user "Package Geometry/Pastemask Top")
		(15 "B.Paste" user "Package Geometry/Pastemask Bottom")
		(5 "F.SilkS" user "Ref Des/Silkscreen Top")
		(7 "B.SilkS" user "Ref Des/Silkscreen Bottom")
		(1 "F.Mask" user "Board Geometry/Soldermask Top")
		(3 "B.Mask" user "Board Geometry/Soldermask Bottom")
		(17 "Dwgs.User" user "User.Drawings")
		(19 "Cmts.User" user "User.Comments")
		(21 "Eco1.User" user "User.Eco1")
		(23 "Eco2.User" user "User.Eco2")
		(25 "Edge.Cuts" user "Board Geometry/Outline")
		(27 "Margin" user)
		(31 "F.CrtYd" user "Package Geometry/Place Bound Top")
		(29 "B.CrtYd" user "Package Geometry/Place Bound Bottom")
		(35 "F.Fab" user "Ref Des/Assembly Top")
		(33 "B.Fab" user "Ref Des/Assembly Bottom")
	)
	(footprint ""
		(layer "B.Cu")
		(at 195.253356 -423.657014 -90)
		(property "Reference" "R4707"
			(at 0 0 90)
			(layer "B.SilkS")
			(hide yes)
			(effects
				(font
					(size 1.27 1.27)
				)
				(justify mirror)
			)
		)
		(property "Value" ""
			(at 0 0 90)
			(layer "B.Fab")
			(effects
				(font
					(size 1.27 1.27)
				)
				(justify mirror)
			)
		)
		(duplicate_pad_numbers_are_jumpers no)
		(fp_line
			(start -0.7874 0.4064)
			(end 0.7874 0.4064)
			(stroke
				(width 0.1524)
				(type default)
			)
			(layer "B.SilkS")
		)
		(fp_line
			(start 0.7874 0.4064)
			(end 0.7874 -0.4064)
			(stroke
				(width 0.1524)
				(type default)
			)
			(layer "B.SilkS")
		)
		(fp_line
			(start -0.7874 -0.4064)
			(end -0.7874 0.4064)
			(stroke
				(width 0.1524)
				(type default)
			)
			(layer "B.SilkS")
		)
		(fp_line
			(start 0.7874 -0.4064)
			(end -0.7874 -0.4064)
			(stroke
				(width 0.1524)
				(type default)
			)
			(layer "B.SilkS")
		)
		(fp_line
			(start -0.67945 0.3048)
			(end -0.120396 0.3048)
			(stroke
				(width 0.1)
				(type default)
			)
			(layer "B.Fab")
		)
		(fp_line
			(start -0.120396 0.3048)
			(end -0.120396 0.2794)
			(stroke
				(width 0.1)
				(type default)
			)
			(layer "B.Fab")
		)
		(fp_line
			(start 0.12065 0.3048)
			(end 0.67945 0.3048)
			(stroke
				(width 0.1)
				(type default)
			)
			(layer "B.Fab")
		)
		(fp_line
			(start 0.67945 0.3048)
			(end 0.67945 -0.305054)
			(stroke
				(width 0.1)
				(type default)
			)
			(layer "B.Fab")
		)
		(fp_line
			(start -0.120396 0.2794)
			(end 0.12065 0.2794)
			(stroke
				(width 0.1)
				(type default)
			)
			(layer "B.Fab")
		)
		(fp_line
			(start 0.12065 0.2794)
			(end 0.12065 0.3048)
			(stroke
				(width 0.1)
				(type default)
			)
			(layer "B.Fab")
		)
		(fp_line
			(start -0.12065 -0.2794)
			(end -0.12065 -0.3048)
			(stroke
				(width 0.1)
				(type default)
			)
			(layer "B.Fab")
		)
		(fp_line
			(start 0.12065 -0.2794)
			(end -0.12065 -0.2794)
			(stroke
				(width 0.1)
				(type default)
			)
			(layer "B.Fab")
		)
		(fp_line
			(start -0.67945 -0.3048)
			(end -0.67945 0.3048)
			(stroke
				(width 0.1)
				(type default)
			)
			(layer "B.Fab")
		)
		(fp_line
			(start -0.12065 -0.3048)
			(end -0.67945 -0.3048)
			(stroke
				(width 0.1)
				(type default)
			)
			(layer "B.Fab")
		)
		(fp_line
			(start 0.12065 -0.305054)
			(end 0.12065 -0.2794)
			(stroke
				(width 0.1)
				(type default)
			)
			(layer "B.Fab")
		)
		(fp_line
			(start 0.67945 -0.305054)
			(end 0.12065 -0.305054)
			(stroke
				(width 0.1)
				(type default)
			)
			(layer "B.Fab")
		)
		(pad "1" smd circle
			(at 0.40005 0 90)
			(size 0 0)
			(layers "B.Cu" "B.Mask" "B.Paste")
			(net "LED_P12V_PSU_R3")
		)
		(pad "2" smd circle
			(at -0.40005 0 90)
			(size 0 0)
			(layers "B.Cu" "B.Mask" "B.Paste")
			(net "P12V_PSU")
		)
	)
	(footprint ""
		(layer "B.Cu")
		(at 78.223618 -184.110376 90)
		(property "Reference" "R341"
			(at 0 0 90)
			(layer "B.SilkS")
			(hide yes)
			(effects
				(font
					(size 1.27 1.27)
				)
				(justify mirror)
			)
		)
		(property "Value" ""
			(at 0 0 90)
			(layer "B.Fab")
			(effects
				(font
					(size 1.27 1.27)
				)
				(justify mirror)
			)
		)
		(duplicate_pad_numbers_are_jumpers no)
		(fp_line
			(start 0.7874 -0.4064)
			(end -0.7874 -0.4064)
			(stroke
				(width 0.1524)
				(type default)
			)
			(layer "B.SilkS")
		)
		(fp_line
			(start -0.7874 -0.4064)
			(end -0.7874 0.4064)
			(stroke
				(width 0.1524)
				(type default)
			)
			(layer "B.SilkS")
		)
		(fp_line
			(start 0.7874 0.4064)
			(end 0.7874 -0.4064)
			(stroke
				(width 0.1524)
				(type default)
			)
			(layer "B.SilkS")
		)
		(fp_line
			(start -0.7874 0.4064)
			(end 0.7874 0.4064)
			(stroke
				(width 0.1524)
				(type default)
			)
			(layer "B.SilkS")
		)
		(fp_line
			(start 0.67945 -0.305054)
			(end 0.12065 -0.305054)
			(stroke
				(width 0.1)
				(type default)
			)
			(layer "B.Fab")
		)
		(fp_line
			(start 0.12065 -0.305054)
			(end 0.12065 -0.2794)
			(stroke
				(width 0.1)
				(type default)
			)
			(layer "B.Fab")
		)
		(fp_line
			(start -0.12065 -0.3048)
			(end -0.67945 -0.3048)
			(stroke
				(width 0.1)
				(type default)
			)
			(layer "B.Fab")
		)
		(fp_line
			(start -0.67945 -0.3048)
			(end -0.67945 0.3048)
			(stroke
				(width 0.1)
				(type default)
			)
			(layer "B.Fab")
		)
		(fp_line
			(start 0.12065 -0.2794)
			(end -0.12065 -0.2794)
			(stroke
				(width 0.1)
				(type default)
			)
			(layer "B.Fab")
		)
		(fp_line
			(start -0.12065 -0.2794)
			(end -0.12065 -0.3048)
			(stroke
				(width 0.1)
				(type default)
			)
			(layer "B.Fab")
		)
		(fp_line
			(start 0.12065 0.2794)
			(end 0.12065 0.3048)
			(stroke
				(width 0.1)
				(type default)
			)
			(layer "B.Fab")
		)
		(fp_line
			(start -0.120396 0.2794)
			(end 0.12065 0.2794)
			(stroke
				(width 0.1)
				(type default)
			)
			(layer "B.Fab")
		)
		(fp_line
			(start 0.67945 0.3048)
			(end 0.67945 -0.305054)
			(stroke
				(width 0.1)
				(type default)
			)
			(layer "B.Fab")
		)
		(fp_line
			(start 0.12065 0.3048)
			(end 0.67945 0.3048)
			(stroke
				(width 0.1)
				(type default)
			)
			(layer "B.Fab")
		)
		(fp_line
			(start -0.120396 0.3048)
			(end -0.120396 0.2794)
			(stroke
				(width 0.1)
				(type default)
			)
			(layer "B.Fab")
		)
		(fp_line
			(start -0.67945 0.3048)
			(end -0.120396 0.3048)
			(stroke
				(width 0.1)
				(type default)
			)
			(layer "B.Fab")
		)
		(pad "1" smd circle
			(at 0.40005 0 270)
			(size 0 0)
			(layers "B.Cu" "B.Mask" "B.Paste")
			(net "H_CPU1_ERR1_LVC1_R_N")
		)
		(pad "2" smd circle
			(at -0.40005 0 270)
			(size 0 0)
			(layers "B.Cu" "B.Mask" "B.Paste")
			(net "H_CPU_ERR1_LVC1_R_N")
		)
	)
	(footprint ""
		(layer "B.Cu")
		(at 376.518932 -80.354424 180)
		(property "Reference" "PC1237"
			(at 0 0 0)
			(layer "B.SilkS")
			(hide yes)
			(effects
				(font
					(size 1.27 1.27)
				)
				(justify mirror)
			)
		)
		(property "Value" ""
			(at 0 0 0)
			(layer "B.Fab")
			(effects
				(font
					(size 1.27 1.27)
				)
				(justify mirror)
			)
		)
		(duplicate_pad_numbers_are_jumpers no)
		(fp_line
			(start 1.524 0.762)
			(end 1.524 -0.762)
			(stroke
				(width 0.1524)
				(type default)
			)
			(layer "B.SilkS")
		)
		(fp_line
			(start 1.524 -0.762)
			(end -1.524 -0.762)
			(stroke
				(width 0.1524)
				(type default)
			)
			(layer "B.SilkS")
		)
		(fp_line
			(start -1.524 0.762)
			(end 1.524 0.762)
			(stroke
				(width 0.1524)
				(type default)
			)
			(layer "B.SilkS")
		)
		(fp_line
			(start -1.524 -0.762)
			(end -1.524 0.762)
			(stroke
				(width 0.1524)
				(type default)
			)
			(layer "B.SilkS")
		)
		(fp_line
			(start 1.1049 0.724916)
			(end -1.1049 0.724916)
			(stroke
				(width 0.1)
				(type default)
			)
			(layer "B.Fab")
		)
		(fp_line
			(start 1.1049 -0.724916)
			(end 1.1049 0.724916)
			(stroke
				(width 0.1)
				(type default)
			)
			(layer "B.Fab")
		)
		(fp_line
			(start -1.1049 0.724916)
			(end -1.1049 -0.724916)
			(stroke
				(width 0.1)
				(type default)
			)
			(layer "B.Fab")
		)
		(fp_line
			(start -1.1049 -0.724916)
			(end 1.1049 -0.724916)
			(stroke
				(width 0.1)
				(type default)
			)
			(layer "B.Fab")
		)
		(pad "1" smd rect
			(at 0.889 0 180)
			(size 1.016 1.27)
			(layers "B.Cu" "B.Mask" "B.Paste")
			(net "P1V8_PCH_AUX")
		)
		(pad "2" smd rect
			(at -0.889 0 180)
			(size 1.016 1.27)
			(layers "B.Cu" "B.Mask" "B.Paste")
			(net "GND")
		)
	)
)
